# S9S_MB_2U (Grand Teton) — schematic netlist excerpt (pin names and nets, part order shuffled) for the footprints in the layout excerpt that follows; sources: Cadence DE-HDL packaged netlist, KiCad conversion of 03242023_DA0F0TMBIJ0_F0T_Motherboard_J_brd_V01_OCP.brd

C713  Q_CAP_DIFFBUS  DIFF BUS_0.22UF 6.3V 20% X6S  pkg C0201  page 176 : \1\ = P5E_CPU1_PE0_TX_C_DP<14> ; \2\ = P5E_CPU1_PE0_TX_DP<14>
R2703  Q_RES  0 5% CHIP  pkg 0402LF  page 231 : A = SMB_BMC_SWB_SCL_R4 ; B = SMB_BMC_SWB_SCL
C2285  Q_CAP  0.1UF 25V 10% X7R  pkg 0402  page 169 : A = P3V3_AUX_USB_BUF ; B = GND

(kicad_pcb
	(version 20260206)
	(generator "pcbnew")
	(generator_version "10.0")
	(general
		(thickness 1.6)
		(legacy_teardrops no)
	)
	(paper "A4")
	(title_block
		(title "03242023_DA0F0TMBIJ0_F0T_Motherboard_J_brd_V01_OCP.brd")
		(comment 1 "Grand Teton / footprints 1241-1243 of 6105")
	)
	(layers
		(0 "F.Cu" signal "TOP")
		(4 "In1.Cu" signal "GND")
		(6 "In2.Cu" signal "IN1")
		(8 "In3.Cu" signal "GND1")
		(10 "In4.Cu" signal "IN2")
		(12 "In5.Cu" signal "GND2")
		(14 "In6.Cu" signal "IN3")
		(16 "In7.Cu" signal "GND3")
		(18 "In8.Cu" signal "VCC")
		(20 "In9.Cu" signal "VCC1")
		(22 "In10.Cu" signal "GND4")
		(24 "In11.Cu" signal "IN4")
		(26 "In12.Cu" signal "GND5")
		(28 "In13.Cu" signal "IN5")
		(30 "In14.Cu" signal "GND6")
		(32 "In15.Cu" signal "IN6")
		(34 "In16.Cu" signal "GND7")
		(2 "B.Cu" signal "BOTTOM")
		(9 "F.Adhes" user "F.Adhesive")
		(11 "B.Adhes" user "B.Adhesive")
		(13 "F.Paste" user "Package Geometry/Pastemask Top")
		(15 "B.Paste" user "Package Geometry/Pastemask Bottom")
		(5 "F.SilkS" user "Ref Des/Silkscreen Top")
		(7 "B.SilkS" user "Ref Des/Silkscreen Bottom")
		(1 "F.Mask" user "Board Geometry/Soldermask Top")
		(3 "B.Mask" user "Board Geometry/Soldermask Bottom")
		(17 "Dwgs.User" user "User.Drawings")
		(19 "Cmts.User" user "User.Comments")
		(21 "Eco1.User" user "User.Eco1")
		(23 "Eco2.User" user "User.Eco2")
		(25 "Edge.Cuts" user "Board Geometry/Outline")
		(27 "Margin" user)
		(31 "F.CrtYd" user "Package Geometry/Place Bound Top")
		(29 "B.CrtYd" user "Package Geometry/Place Bound Bottom")
		(35 "F.Fab" user "Ref Des/Assembly Top")
		(33 "B.Fab" user "Ref Des/Assembly Bottom")
	)
	(footprint ""
		(layer "F.Cu")
		(at 129.75082 -27.348688 -90)
		(property "Reference" "C2285"
			(at 0 0 270)
			(layer "F.SilkS")
			(hide yes)
			(effects
				(font
					(size 1.27 1.27)
				)
			)
		)
		(property "Value" ""
			(at 0 0 270)
			(layer "F.Fab")
			(effects
				(font
					(size 1.27 1.27)
				)
			)
		)
		(duplicate_pad_numbers_are_jumpers no)
		(fp_line
			(start -0.7874 0.4064)
			(end -0.7874 -0.4064)
			(stroke
				(width 0.1524)
				(type default)
			)
			(layer "F.SilkS")
		)
		(fp_line
			(start 0.7874 0.4064)
			(end -0.7874 0.4064)
			(stroke
				(width 0.1524)
				(type default)
			)
			(layer "F.SilkS")
		)
		(fp_line
			(start -0.7874 -0.4064)
			(end 0.7874 -0.4064)
			(stroke
				(width 0.1524)
				(type default)
			)
			(layer "F.SilkS")
		)
		(fp_line
			(start 0.7874 -0.4064)
			(end 0.7874 0.4064)
			(stroke
				(width 0.1524)
				(type default)
			)
			(layer "F.SilkS")
		)
		(fp_line
			(start -0.67945 0.3048)
			(end -0.67945 -0.305054)
			(stroke
				(width 0.1)
				(type default)
			)
			(layer "F.Fab")
		)
		(fp_line
			(start -0.12065 0.3048)
			(end -0.67945 0.3048)
			(stroke
				(width 0.1)
				(type default)
			)
			(layer "F.Fab")
		)
		(fp_line
			(start 0.120396 0.3048)
			(end 0.120396 0.2794)
			(stroke
				(width 0.1)
				(type default)
			)
			(layer "F.Fab")
		)
		(fp_line
			(start 0.67945 0.3048)
			(end 0.120396 0.3048)
			(stroke
				(width 0.1)
				(type default)
			)
			(layer "F.Fab")
		)
		(fp_line
			(start -0.12065 0.2794)
			(end -0.12065 0.3048)
			(stroke
				(width 0.1)
				(type default)
			)
			(layer "F.Fab")
		)
		(fp_line
			(start 0.120396 0.2794)
			(end -0.12065 0.2794)
			(stroke
				(width 0.1)
				(type default)
			)
			(layer "F.Fab")
		)
		(fp_line
			(start -0.12065 -0.2794)
			(end 0.12065 -0.2794)
			(stroke
				(width 0.1)
				(type default)
			)
			(layer "F.Fab")
		)
		(fp_line
			(start 0.12065 -0.2794)
			(end 0.12065 -0.3048)
			(stroke
				(width 0.1)
				(type default)
			)
			(layer "F.Fab")
		)
		(fp_line
			(start 0.12065 -0.3048)
			(end 0.67945 -0.3048)
			(stroke
				(width 0.1)
				(type default)
			)
			(layer "F.Fab")
		)
		(fp_line
			(start 0.67945 -0.3048)
			(end 0.67945 0.3048)
			(stroke
				(width 0.1)
				(type default)
			)
			(layer "F.Fab")
		)
		(fp_line
			(start -0.67945 -0.305054)
			(end -0.12065 -0.305054)
			(stroke
				(width 0.1)
				(type default)
			)
			(layer "F.Fab")
		)
		(fp_line
			(start -0.12065 -0.305054)
			(end -0.12065 -0.2794)
			(stroke
				(width 0.1)
				(type default)
			)
			(layer "F.Fab")
		)
		(pad "1" smd circle
			(at -0.40005 0 270)
			(size 0 0)
			(layers "F.Cu" "F.Mask" "F.Paste")
			(net "P3V3_AUX_USB_BUF")
		)
		(pad "2" smd circle
			(at 0.40005 0 270)
			(size 0 0)
			(layers "F.Cu" "F.Mask" "F.Paste")
			(net "GND")
		)
	)
	(footprint ""
		(layer "F.Cu")
		(at 51.932078 -402.371052 -90)
		(property "Reference" "C713"
			(at 0 0 270)
			(layer "F.SilkS")
			(hide yes)
			(effects
				(font
					(size 1.27 1.27)
				)
			)
		)
		(property "Value" ""
			(at 0 0 270)
			(layer "F.Fab")
			(effects
				(font
					(size 1.27 1.27)
				)
			)
		)
		(duplicate_pad_numbers_are_jumpers no)
		(fp_line
			(start -0.299974 0.150114)
			(end -0.299974 -0.150114)
			(stroke
				(width 0.1)
				(type default)
			)
			(layer "F.Fab")
		)
		(fp_line
			(start 0.299974 0.150114)
			(end -0.299974 0.150114)
			(stroke
				(width 0.1)
				(type default)
			)
			(layer "F.Fab")
		)
		(fp_line
			(start -0.299974 -0.150114)
			(end 0.299974 -0.150114)
			(stroke
				(width 0.1)
				(type default)
			)
			(layer "F.Fab")
		)
		(fp_line
			(start 0.299974 -0.150114)
			(end 0.299974 0.150114)
			(stroke
				(width 0.1)
				(type default)
			)
			(layer "F.Fab")
		)
		(pad "1" smd rect
			(at -0.2667 0 270)
			(size 0.3048 0.381)
			(layers "F.Cu" "F.Mask" "F.Paste")
			(net "P5E_CPU1_PE0_TX_C_DP<14>")
		)
		(pad "2" smd rect
			(at 0.2667 0 270)
			(size 0.3048 0.381)
			(layers "F.Cu" "F.Mask" "F.Paste")
			(net "P5E_CPU1_PE0_TX_DP<14>")
		)
	)
	(footprint ""
		(layer "F.Cu")
		(at 128.401572 -130.002026)
		(property "Reference" "R2703"
			(at 0 0 0)
			(layer "F.SilkS")
			(hide yes)
			(effects
				(font
					(size 1.27 1.27)
				)
			)
		)
		(property "Value" ""
			(at 0 0 0)
			(layer "F.Fab")
			(effects
				(font
					(size 1.27 1.27)
				)
			)
		)
		(duplicate_pad_numbers_are_jumpers no)
		(fp_line
			(start -0.7874 -0.4064)
			(end 0.7874 -0.4064)
			(stroke
				(width 0.1524)
				(type default)
			)
			(layer "F.SilkS")
		)
		(fp_line
			(start -0.7874 0.4064)
			(end -0.7874 -0.4064)
			(stroke
				(width 0.1524)
				(type default)
			)
			(layer "F.SilkS")
		)
		(fp_line
			(start 0.7874 -0.4064)
			(end 0.7874 0.4064)
			(stroke
				(width 0.1524)
				(type default)
			)
			(layer "F.SilkS")
		)
		(fp_line
			(start 0.7874 0.4064)
			(end -0.7874 0.4064)
			(stroke
				(width 0.1524)
				(type default)
			)
			(layer "F.SilkS")
		)
		(fp_line
			(start -0.67945 -0.305054)
			(end -0.12065 -0.305054)
			(stroke
				(width 0.1)
				(type default)
			)
			(layer "F.Fab")
		)
		(fp_line
			(start -0.67945 0.3048)
			(end -0.67945 -0.305054)
			(stroke
				(width 0.1)
				(type default)
			)
			(layer "F.Fab")
		)
		(fp_line
			(start -0.12065 -0.305054)
			(end -0.12065 -0.2794)
			(stroke
				(width 0.1)
				(type default)
			)
			(layer "F.Fab")
		)
		(fp_line
			(start -0.12065 -0.2794)
			(end 0.12065 -0.2794)
			(stroke
				(width 0.1)
				(type default)
			)
			(layer "F.Fab")
		)
		(fp_line
			(start -0.12065 0.2794)
			(end -0.12065 0.3048)
			(stroke
				(width 0.1)
				(type default)
			)
			(layer "F.Fab")
		)
		(fp_line
			(start -0.12065 0.3048)
			(end -0.67945 0.3048)
			(stroke
				(width 0.1)
				(type default)
			)
			(layer "F.Fab")
		)
		(fp_line
			(start 0.120396 0.2794)
			(end -0.12065 0.2794)
			(stroke
				(width 0.1)
				(type default)
			)
			(layer "F.Fab")
		)
		(fp_line
			(start 0.120396 0.3048)
			(end 0.120396 0.2794)
			(stroke
				(width 0.1)
				(type default)
			)
			(layer "F.Fab")
		)
		(fp_line
			(start 0.12065 -0.3048)
			(end 0.67945 -0.3048)
			(stroke
				(width 0.1)
				(type default)
			)
			(layer "F.Fab")
		)
		(fp_line
			(start 0.12065 -0.2794)
			(end 0.12065 -0.3048)
			(stroke
				(width 0.1)
				(type default)
			)
			(layer "F.Fab")
		)
		(fp_line
			(start 0.67945 -0.3048)
			(end 0.67945 0.3048)
			(stroke
				(width 0.1)
				(type default)
			)
			(layer "F.Fab")
		)
		(fp_line
			(start 0.67945 0.3048)
			(end 0.120396 0.3048)
			(stroke
				(width 0.1)
				(type default)
			)
			(layer "F.Fab")
		)
		(pad "1" smd circle
			(at -0.40005 0)
			(size 0 0)
			(layers "F.Cu" "F.Mask" "F.Paste")
			(net "SMB_BMC_SWB_SCL_R4")
		)
		(pad "2" smd circle
			(at 0.40005 0)
			(size 0 0)
			(layers "F.Cu" "F.Mask" "F.Paste")
			(net "SMB_BMC_SWB_SCL")
		)
	)
)
